# T6G (Grand Teton) — schematic netlist excerpt (pin names and nets, part order shuffled) for the footprints in the layout excerpt that follows; sources: Cadence DE-HDL packaged netlist, KiCad conversion of 04192023_DAF0TMB3IC0_F0TG_MB_C_brd_V02_OCP.brd

J16  SCONN288_DDR506112002KQ  IO  pkg DDR288S_1-1VXC  page 92
  VIN_BULK0  = P12V_MEM_CPU0
  RFU0  = NC
  VIN_MGMT  = P3V3_AUX
  HSCL  = I3C_SPD_DDRG_CPU0_SCL
  HSDA  = I3C_SPD_DDRG_CPU0_SDA
  VSS0  = GND
  DQ0_A  = M_G_CPU0_SA_DQ<0>
  VSS1  = GND
  DQ1_A  = M_G_CPU0_SA_DQ<1>
  VSS2  = GND
  DQS0_A_T  = M_G_CPU0_SA_DQS_DP<0>
  DQS0_A_C  = M_G_CPU0_SA_DQS_DN<0>
  VSS3  = GND
  DQ4_A  = M_G_CPU0_SA_DQ<4>
  VSS4  = GND
  DQ5_A  = M_G_CPU0_SA_DQ<5>
  VSS5  = GND
  DQ8_A  = M_G_CPU0_SA_DQ<8>
  VSS6  = GND
  DQ9_A  = M_G_CPU0_SA_DQ<9>
  VSS7  = GND
  DQS1_A_T  = M_G_CPU0_SA_DQS_DP<1>
  DQS1_A_C  = M_G_CPU0_SA_DQS_DN<1>
  VSS8  = GND
  DQ12_A  = M_G_CPU0_SA_DQ<12>
  VSS9  = GND
  DQ13_A  = M_G_CPU0_SA_DQ<13>
  VSS10  = GND
  DQ16_A  = M_G_CPU0_SA_DQ<16>
  VSS11  = GND
  DQ17_A  = M_G_CPU0_SA_DQ<17>
  VSS12  = GND
  DQS2_A_T  = M_G_CPU0_SA_DQS_DP<2>
  DQS2_A_C  = M_G_CPU0_SA_DQS_DN<2>
  VSS13  = GND
  DQ20_A  = M_G_CPU0_SA_DQ<20>
  VSS14  = GND
  DQ21_A  = M_G_CPU0_SA_DQ<21>
  VSS15  = GND
  DQ24_A  = M_G_CPU0_SA_DQ<24>
  VSS16  = GND
  DQ25_A  = M_G_CPU0_SA_DQ<25>
  VSS17  = GND
  DQS3_A_T  = M_G_CPU0_SA_DQS_DP<3>
  DQS3_A_C  = M_G_CPU0_SA_DQS_DN<3>
  VSS18  = GND
  DQ28_A  = M_G_CPU0_SA_DQ<28>
  VSS19  = GND
  DQ29_A  = M_G_CPU0_SA_DQ<29>
  VSS20  = GND
  CB0_A  = M_G_CPU0_SA_CB<0>
  VSS21  = GND
  CB1_A  = M_G_CPU0_SA_CB<1>
  VSS22  = GND
  DQS4_A_T  = M_G_CPU0_SA_DQS_DP<4>
  DQS4_A_C  = M_G_CPU0_SA_DQS_DN<4>
  VSS23  = GND
  CB4_A  = M_G_CPU0_SA_CB<4>
  VSS24  = GND
  CB5_A  = M_G_CPU0_SA_CB<5>
  VSS25  = GND
  ALERT_N  = M_G_CPU0_ALERT_N
  VSS26  = GND
  CS0_A_N  = M_G_CPU0_SA_CS_N<0>
  VSS27  = GND
  CA0_A  = M_G_CPU0_SA_CA<0>
  VSS28  = GND
  CA2_A  = M_G_CPU0_SA_CA<2>
  VSS29  = GND
  CA4_A  = M_G_CPU0_SA_CA<4>
  VSS30  = GND
  CA6_A  = M_G_CPU0_SA_CA<6>
  VSS31  = GND
  PAR_A  = M_G_CPU0_SA_PAR
  VSS32  = GND
  CA0_B  = M_G_CPU0_SB_CA<0>
  VSS33  = GND
  CA2_B  = M_G_CPU0_SB_CA<2>
  VSS34  = GND
  CA4_B  = M_G_CPU0_SB_CA<4>
  VSS35  = GND
  CA6_B  = M_G_CPU0_SB_CA<6>
  VSS36  = GND
  CS0_B_N  = M_G_CPU0_SB_CS_N<0>
  VSS37  = GND
  \lbd||rsp_a_n\  = M_G_CPU0_SA_RSP<0>
  \lbs||rsp_b_n\  = M_G_CPU0_SB_RSP<0>
  VSS38  = GND
  CB4_B  = M_G_CPU0_SB_CB<4>
  VSS39  = GND
  CB5_B  = M_G_CPU0_SB_CB<5>
  VSS40  = GND
  \dqs9_b_t||tdqs9_b_t||dbi4_b_n\  = M_G_CPU0_SB_DQS_DP<9>
  \dqs9_b_c||tdqs9_b_c\  = M_G_CPU0_SB_DQS_DN<9>
  VSS41  = GND
  CB0_B  = M_G_CPU0_SB_CB<0>
  VSS42  = GND
  CB1_B  = M_G_CPU0_SB_CB<1>
  VSS43  = GND
  DQ0_B  = M_G_CPU0_SB_DQ<0>
  VSS44  = GND
  DQ1_B  = M_G_CPU0_SB_DQ<1>
  VSS45  = GND
  DQS0_B_T  = M_G_CPU0_SB_DQS_DP<0>
  DQS0_B_C  = M_G_CPU0_SB_DQS_DN<0>
  VSS46  = GND
  DQ4_B  = M_G_CPU0_SB_DQ<4>
  VSS47  = GND
  DQ5_B  = M_G_CPU0_SB_DQ<5>
  VSS48  = GND
  DQ8_B  = M_G_CPU0_SB_DQ<8>
  VSS49  = GND
  DQ9_B  = M_G_CPU0_SB_DQ<9>
  VSS50  = GND
  DQS1_B_T  = M_G_CPU0_SB_DQS_DP<1>
  DQS1_B_C  = M_G_CPU0_SB_DQS_DN<1>
  VSS51  = GND
  DQ12_B  = M_G_CPU0_SB_DQ<12>
  VSS52  = GND
  DQ13_B  = M_G_CPU0_SB_DQ<13>
  VSS53  = GND
  DQ16_B  = M_G_CPU0_SB_DQ<16>
  VSS54  = GND
  DQ17_B  = M_G_CPU0_SB_DQ<17>
  VSS55  = GND
  DQS2_B_T  = M_G_CPU0_SB_DQS_DP<2>
  DQS2_B_C  = M_G_CPU0_SB_DQS_DN<2>
  VSS56  = GND
  DQ20_B  = M_G_CPU0_SB_DQ<20>
  VSS57  = GND
  DQ21_B  = M_G_CPU0_SB_DQ<21>
  VSS58  = GND
  DQ24_B  = M_G_CPU0_SB_DQ<24>
  VSS59  = GND
  DQ25_B  = M_G_CPU0_SB_DQ<25>
  VSS60  = GND
  DQS3_B_T  = M_G_CPU0_SB_DQS_DP<3>
  DQS3_B_C  = M_G_CPU0_SB_DQS_DN<3>
  VSS61  = GND
  DQ28_B  = M_G_CPU0_SB_DQ<28>
  VSS62  = GND
  DQ29_B  = M_G_CPU0_SB_DQ<29>
  VSS63  = GND
  RFU1  = NC
  VIN_BULK1  = P12V_MEM_CPU0
  VIN_BULK2  = P12V_MEM_CPU0
  \pwr_good||fail_n\  = PWRGD_CHG_CPU0_DIMM0
  HAS  = PD_CHG_CPU0_DIMM0_SAA
  RFU2  = NC
  RFU3  = NC
  VSS64  = GND
  DQ2_A  = M_G_CPU0_SA_DQ<2>
  VSS65  = GND
  DQ3_A  = M_G_CPU0_SA_DQ<3>
  VSS66  = GND
  \dqs5_a_c||tdqs5_a_c||dqs5_a_t||tdqs5_a_t\  = M_G_CPU0_SA_DQS_DN<5>
  \dqs5_a_t||tdqs5_a_t\  = M_G_CPU0_SA_DQS_DP<5>
  VSS67  = GND
  DQ6_A  = M_G_CPU0_SA_DQ<6>
  VSS68  = GND
  DQ7_A  = M_G_CPU0_SA_DQ<7>
  VSS69  = GND
  DQ10_A  = M_G_CPU0_SA_DQ<10>
  VSS70  = GND
  DQ11_A  = M_G_CPU0_SA_DQ<11>
  VSS71  = GND
  \dqs6_a_c||tdqs6_a_c||dqs6_a_t||tdqs6_a_t\  = M_G_CPU0_SA_DQS_DN<6>
  \dqs6_a_t||tdqs6_a_t\  = M_G_CPU0_SA_DQS_DP<6>
  VSS72  = GND
  DQ14_A  = M_G_CPU0_SA_DQ<14>
  VSS73  = GND
  DQ15_A  = M_G_CPU0_SA_DQ<15>
  VSS74  = GND
  DQ18_A  = M_G_CPU0_SA_DQ<18>
  VSS75  = GND
  DQ19_A  = M_G_CPU0_SA_DQ<19>
  VSS76  = GND
  \dqs7_a_c||tdqs7_a_c\  = M_G_CPU0_SA_DQS_DN<7>
  \dqs7_a_t||tdqs7_a_t\  = M_G_CPU0_SA_DQS_DP<7>
  VSS77  = GND
  DQ22_A  = M_G_CPU0_SA_DQ<22>
  VSS78  = GND
  DQ23_A  = M_G_CPU0_SA_DQ<23>
  VSS79  = GND
  DQ26_A  = M_G_CPU0_SA_DQ<26>
  VSS80  = GND
  DQ27_A  = M_G_CPU0_SA_DQ<27>
  VSS81  = GND
  \dqs8_a_c||tdqs8_a_c\  = M_G_CPU0_SA_DQS_DN<8>
  \dqs8_a_t||tdqs8_a_t\  = M_G_CPU0_SA_DQS_DP<8>
  VSS82  = GND
  DQ30_A  = M_G_CPU0_SA_DQ<30>
  VSS83  = GND
  DQ31_A  = M_G_CPU0_SA_DQ<31>
  VSS84  = GND
  CB2_A  = M_G_CPU0_SA_CB<2>
  VSS85  = GND
  CB3_A  = M_G_CPU0_SA_CB<3>
  VSS86  = GND
  \dqs9_a_c||tdqs9_a_c\  = M_G_CPU0_SA_DQS_DN<9>
  \dqs9_a_t||tdqs9_a_t\  = M_G_CPU0_SA_DQS_DP<9>
  VSS87  = GND
  CB6_A  = M_G_CPU0_SA_CB<6>
  VSS88  = GND
  CB7_A  = M_G_CPU0_SA_CB<7>
  VSS89  = GND
  RESET_N  = M_G_CPU0_RESET_N
  VSS90  = GND
  CS1_A_N  = M_G_CPU0_SA_CS_N<1>
  VSS91  = GND
  CA1_A  = M_G_CPU0_SA_CA<1>
  VSS92  = GND
  CA3_A  = M_G_CPU0_SA_CA<3>
  VSS93  = GND
  CA5_A  = M_G_CPU0_SA_CA<5>
  VSS94  = GND
  CK_T  = M_G_CPU0_CLK_DP<0>
  CK_C  = M_G_CPU0_CLK_DN<0>
  VSS95  = GND
  RFU4  = NC
  CA1_B  = M_G_CPU0_SB_CA<1>
  VSS96  = GND
  CA3_B  = M_G_CPU0_SB_CA<3>
  VSS97  = GND
  CA5_B  = M_G_CPU0_SB_CA<5>
  VSS98  = GND
  PAR_B  = M_G_CPU0_SB_PAR
  VSS99  = GND
  CS1_B_N  = M_G_CPU0_SB_CS_N<1>
  VSS100  = GND
  RFU5  = NC
  RFU6  = NC
  VSS101  = GND
  CB6_B  = M_G_CPU0_SB_CB<6>
  VSS102  = GND
  CB7_B  = M_G_CPU0_SB_CB<7>
  VSS103  = GND
  DQS4_B_C  = M_G_CPU0_SB_DQS_DN<4>
  DQS4_B_T  = M_G_CPU0_SB_DQS_DP<4>
  VSS104  = GND
  CB2_B  = M_G_CPU0_SB_CB<2>
  VSS105  = GND
  CB3_B  = M_G_CPU0_SB_CB<3>
  VSS106  = GND
  DQ2_B  = M_G_CPU0_SB_DQ<2>
  VSS107  = GND
  DQ3_B  = M_G_CPU0_SB_DQ<3>
  VSS108  = GND
  \dqs5_b_c||tdqs5_b_c\  = M_G_CPU0_SB_DQS_DN<5>
  \dqs5_b_t||tdqs5_b_t\  = M_G_CPU0_SB_DQS_DP<5>
  VSS109  = GND
  DQ6_B  = M_G_CPU0_SB_DQ<6>
  VSS110  = GND
  DQ7_B  = M_G_CPU0_SB_DQ<7>
  VSS111  = GND
  DQ10_B  = M_G_CPU0_SB_DQ<10>
  VSS112  = GND
  DQ11_B  = M_G_CPU0_SB_DQ<11>
  VSS113  = GND
  \dqs6_b_c||tdqs6_b_c\  = M_G_CPU0_SB_DQS_DN<6>
  \dqs6_b_t||tdqs6_b_t\  = M_G_CPU0_SB_DQS_DP<6>
  VSS114  = GND
  DQ14_B  = M_G_CPU0_SB_DQ<14>
  VSS115  = GND
  DQ15_B  = M_G_CPU0_SB_DQ<15>
  VSS116  = GND
  DQ18_B  = M_G_CPU0_SB_DQ<18>
  VSS117  = GND
  DQ19_B  = M_G_CPU0_SB_DQ<19>
  VSS118  = GND
  \dqs7_b_c||tdqs7_b_c\  = M_G_CPU0_SB_DQS_DN<7>
  \dqs7_b_t||tdqs7_b_t\  = M_G_CPU0_SB_DQS_DP<7>
  VSS119  = GND
  DQ22_B  = M_G_CPU0_SB_DQ<22>
  VSS120  = GND
  DQ23_B  = M_G_CPU0_SB_DQ<23>
  VSS121  = GND
  DQ26_B  = M_G_CPU0_SB_DQ<26>
  VSS122  = GND
  DQ27_B  = M_G_CPU0_SB_DQ<27>
  VSS123  = GND
  \dqs8_b_c||tdqs8_b_c\  = M_G_CPU0_SB_DQS_DN<8>
  \dqs8_b_t||tdqs8_b_t\  = M_G_CPU0_SB_DQS_DP<8>
  VSS124  = GND
  DQ30_B  = M_G_CPU0_SB_DQ<30>
  VSS125  = GND
  DQ31_B  = M_G_CPU0_SB_DQ<31>
  VSS126  = GND
  G1  = GND
  G2  = GND
  G3  = GND

(kicad_pcb
	(version 20260206)
	(generator "pcbnew")
	(generator_version "10.0")
	(general
		(thickness 1.6)
		(legacy_teardrops no)
	)
	(paper "A4")
	(title_block
		(title "04192023_DAF0TMB3IC0_F0TG_MB_C_brd_V02_OCP.brd")
		(comment 1 "Grand Teton / footprint 1808 of 8354 (J16), pads 277-291 of 291")
	)
	(layers
		(0 "F.Cu" signal "TOP")
		(4 "In1.Cu" signal "GND")
		(6 "In2.Cu" signal "IN1")
		(8 "In3.Cu" signal "GND1")
		(10 "In4.Cu" signal "IN2")
		(12 "In5.Cu" signal "GND2")
		(14 "In6.Cu" signal "IN3")
		(16 "In7.Cu" signal "GND3")
		(18 "In8.Cu" signal "VCC")
		(20 "In9.Cu" signal "VCC1")
		(22 "In10.Cu" signal "GND4")
		(24 "In11.Cu" signal "IN4")
		(26 "In12.Cu" signal "GND5")
		(28 "In13.Cu" signal "IN5")
		(30 "In14.Cu" signal "GND6")
		(32 "In15.Cu" signal "IN6")
		(34 "In16.Cu" signal "GND7")
		(2 "B.Cu" signal "BOTTOM")
		(9 "F.Adhes" user "F.Adhesive")
		(11 "B.Adhes" user "B.Adhesive")
		(13 "F.Paste" user "Package Geometry/Pastemask Top")
		(15 "B.Paste" user "Package Geometry/Pastemask Bottom")
		(5 "F.SilkS" user "Ref Des/Silkscreen Top")
		(7 "B.SilkS" user "Ref Des/Silkscreen Bottom")
		(1 "F.Mask" user "Board Geometry/Soldermask Top")
		(3 "B.Mask" user "Board Geometry/Soldermask Bottom")
		(17 "Dwgs.User" user "User.Drawings")
		(19 "Cmts.User" user "User.Comments")
		(21 "Eco1.User" user "User.Eco1")
		(23 "Eco2.User" user "User.Eco2")
		(25 "Edge.Cuts" user "Board Geometry/Outline")
		(27 "Margin" user)
		(31 "F.CrtYd" user "Package Geometry/Place Bound Top")
		(29 "B.CrtYd" user "Package Geometry/Place Bound Bottom")
		(35 "F.Fab" user "Ref Des/Assembly Top")
		(33 "B.Fab" user "Ref Des/Assembly Bottom")
	)
	(footprint ""
		(layer "F.Cu")
		(at 414.418018 -255.560068 180)
		(property "Reference" "J16"
			(at 1.474216 81.889092 0)
			(unlocked yes)
			(layer "F.SilkS")
			(effects
				(font
					(size 0.7874 0.5842)
					(thickness 0.1524)
				)
			)
		)
		(property "Value" ""
			(at 0 0 180)
			(layer "F.Fab")
			(effects
				(font
					(size 1.27 1.27)
				)
			)
		)
		(duplicate_pad_numbers_are_jumpers no)
		(pad "277" smd rect
			(at 2.050034 53.975 90)
			(size 0.519938 1.4986)
			(layers "F.Cu" "F.Mask" "F.Paste")
			(net "GND")
		)
		(pad "278" smd rect
			(at 2.050034 54.824884 90)
			(size 0.519938 1.4986)
			(layers "F.Cu" "F.Mask" "F.Paste")
			(net "M_G_CPU0_SB_DQ<26>")
		)
		(pad "279" smd rect
			(at 2.050034 55.675022 90)
			(size 0.519938 1.4986)
			(layers "F.Cu" "F.Mask" "F.Paste")
			(net "GND")
		)
		(pad "280" smd rect
			(at 2.050034 56.524906 90)
			(size 0.519938 1.4986)
			(layers "F.Cu" "F.Mask" "F.Paste")
			(net "M_G_CPU0_SB_DQ<27>")
		)
		(pad "281" smd rect
			(at 2.050034 57.375044 90)
			(size 0.519938 1.4986)
			(layers "F.Cu" "F.Mask" "F.Paste")
			(net "GND")
		)
		(pad "282" smd rect
			(at 2.050034 58.224928 90)
			(size 0.519938 1.4986)
			(layers "F.Cu" "F.Mask" "F.Paste")
			(net "M_G_CPU0_SB_DQS_DN<8>")
		)
		(pad "283" smd rect
			(at 2.050034 59.075066 90)
			(size 0.519938 1.4986)
			(layers "F.Cu" "F.Mask" "F.Paste")
			(net "M_G_CPU0_SB_DQS_DP<8>")
		)
		(pad "284" smd rect
			(at 2.050034 59.92495 90)
			(size 0.519938 1.4986)
			(layers "F.Cu" "F.Mask" "F.Paste")
			(net "GND")
		)
		(pad "285" smd rect
			(at 2.050034 60.775088 90)
			(size 0.519938 1.4986)
			(layers "F.Cu" "F.Mask" "F.Paste")
			(net "M_G_CPU0_SB_DQ<30>")
		)
		(pad "286" smd rect
			(at 2.050034 61.624972 90)
			(size 0.519938 1.4986)
			(layers "F.Cu" "F.Mask" "F.Paste")
			(net "GND")
		)
		(pad "287" smd rect
			(at 2.050034 62.47511 90)
			(size 0.519938 1.4986)
			(layers "F.Cu" "F.Mask" "F.Paste")
			(net "M_G_CPU0_SB_DQ<31>")
		)
		(pad "288" smd rect
			(at 2.050034 63.324994 90)
			(size 0.519938 1.4986)
			(layers "F.Cu" "F.Mask" "F.Paste")
			(net "GND")
		)
		(pad "G1" thru_hole oval
			(at 0 -68.97497 90)
			(size 1.7272 3.4798)
			(drill oval 1.2192 2.4638)
			(layers "*.Cu" "*.Mask")
			(remove_unused_layers no)
			(net "GND")
			(clearance 0.127)
			(thermal_gap 0.127)
		)
		(pad "G2" thru_hole oval
			(at 0 3.875024 90)
			(size 1.7272 3.4798)
			(drill oval 1.2192 2.4638)
			(layers "*.Cu" "*.Mask")
			(remove_unused_layers no)
			(net "GND")
			(clearance 0.127)
			(thermal_gap 0.127)
		)
		(pad "G3" thru_hole oval
			(at 0 68.97497 90)
			(size 1.7272 3.4798)
			(drill oval 1.2192 2.4638)
			(layers "*.Cu" "*.Mask")
			(remove_unused_layers no)
			(net "GND")
			(clearance 0.127)
			(thermal_gap 0.127)
		)
	)
)
